(kicad_pcb
	(version 20221018)
	(generator pcbnew)
	(general
    (thickness 1.7403)
  )
	(paper "A4")
	(title_block
    (title "Data Center RDIMM DDR4 Tester")
    (date "2024-09-30")
    (rev "1.2.4")
		(comment 9 "footprints 154-158 of 690")
	)
	(layers
    (0 "F.Cu" signal)
    (1 "In1.Cu" power)
    (2 "In2.Cu" signal)
    (3 "In3.Cu" power)
    (4 "In4.Cu" power)
    (5 "In5.Cu" signal)
    (6 "In6.Cu" power)
    (7 "In7.Cu" signal)
    (8 "In8.Cu" power)
    (9 "In9.Cu" signal)
    (10 "In10.Cu" power)
    (31 "B.Cu" signal)
    (32 "B.Adhes" user "B.Adhesive")
    (33 "F.Adhes" user "F.Adhesive")
    (34 "B.Paste" user)
    (35 "F.Paste" user)
    (36 "B.SilkS" user "B.Silkscreen")
    (37 "F.SilkS" user "F.Silkscreen")
    (38 "B.Mask" user)
    (39 "F.Mask" user)
    (40 "Dwgs.User" user "User.Drawings")
    (41 "Cmts.User" user "User.Comments")
    (42 "Eco1.User" user "User.Eco1")
    (43 "Eco2.User" user "User.Eco2")
    (44 "Edge.Cuts" user)
    (45 "Margin" user)
    (46 "B.CrtYd" user "B.Courtyard")
    (47 "F.CrtYd" user "F.Courtyard")
    (48 "B.Fab" user)
    (49 "F.Fab" user)
  )
	(footprint "data-center-rdimm-ddr4-tester-footprints:Testpoint_smd_1mm" (layer "F.Cu")
    (at 146.05 124.2 90)
    (property "Author" "Antmicro")
    (property "License" "Apache-2.0")
    (property "MPN" "")
    (property "Manufacturer" "")
    (property "Sheetfile" "supply.kicad_sch")
    (property "Sheetname" "Supply")
    (property "ki_description" "Test Point 1mm")
    (attr exclude_from_pos_files)
    (fp_text reference "PHY1" (at -0.36 -3.35 180) (layer "F.SilkS")
        (effects (font (size 0.7 0.7) (thickness 0.15)) (justify left bottom))
    )
    (fp_text value "TP_1mm_SMD" (at 0 1.4 90) (layer "F.Fab") hide
        (effects (font (size 0.7 0.7) (thickness 0.15)) (justify left bottom))
    )
    (fp_text user "Author: Antmicro" (at -0.5 4 90) (layer "F.Fab") hide
        (effects (font (size 0.7 0.7) (thickness 0.15)) (justify left bottom))
    )
    (fp_text user "${REFERENCE}" (at -0.5 2.8 90) (layer "F.Fab") hide
        (effects (font (size 0.7 0.7) (thickness 0.15)) (justify left bottom))
    )
    (fp_text user "License: Apache-2.0" (at -0.5 5.2 90) (layer "F.Fab") hide
        (effects (font (size 0.7 0.7) (thickness 0.15)) (justify left bottom))
    )
    (pad "1" smd circle (at 0 0 90) (size 1 1) (layers "F.Cu" "F.Mask")
      (net 306 "1V2_SYS") (pinfunction "1") (pintype "passive"))
  )
	(footprint "data-center-rdimm-ddr4-tester-footprints:TPS65295RJET" (layer "F.Cu")
    (at 119.606328 99.280008)
    (property "Author" "Antmicro")
    (property "License" "Apache-2.0")
    (property "MPN" "TPS65295RJET")
    (property "Manufacturer" "Texas Instruments")
    (property "Sheetfile" "supply.kicad_sch")
    (property "Sheetname" "Supply")
    (attr smd)
    (fp_text reference "U2" (at -0.496328 -2.150008) (layer "F.SilkS")
        (effects (font (size 0.7 0.7) (thickness 0.15)) (justify left bottom))
    )
    (fp_text value "TPS65295RJE" (at 0 3.1) (layer "F.Fab") hide
        (effects (font (size 0.7 0.7) (thickness 0.15)) (justify left bottom))
    )
    (fp_text user "${REFERENCE}" (at -2.301 5.108) (layer "F.Fab") hide
        (effects (font (size 0.7 0.7) (thickness 0.15)) (justify left bottom))
    )
    (fp_text user "Author: Antmicro" (at -2.301 6.108) (layer "F.Fab") hide
        (effects (font (size 0.7 0.7) (thickness 0.15)) (justify left bottom))
    )
    (fp_text user "License: Apache-2.0" (at -2.301 7.108) (layer "F.Fab") hide
        (effects (font (size 0.7 0.7) (thickness 0.15)) (justify left bottom))
    )
    (fp_poly
      (pts
        (xy -0.352 0.484)
        (xy -0.551 0.484)
        (xy -0.551 -0.535)
        (xy -0.352 -0.535)
      )

      (stroke (width 0.001) (type solid)) (fill solid) (layer "F.Paste"))
    (fp_poly
      (pts
        (xy -0.352 1.703)
        (xy -0.551 1.703)
        (xy -0.551 0.685)
        (xy -0.352 0.685)
      )

      (stroke (width 0.001) (type solid)) (fill solid) (layer "F.Paste"))
    (fp_poly
      (pts
        (xy 0.099 -0.687)
        (xy -0.1 -0.687)
        (xy -0.1 -1.706)
        (xy 0.099 -1.706)
      )

      (stroke (width 0.001) (type solid)) (fill solid) (layer "F.Paste"))
    (fp_poly
      (pts
        (xy 0.099 0.535)
        (xy -0.1 0.535)
        (xy -0.1 -0.485)
        (xy 0.099 -0.485)
      )

      (stroke (width 0.001) (type solid)) (fill solid) (layer "F.Paste"))
    (fp_poly
      (pts
        (xy 0.548 0.484)
        (xy 0.349 0.484)
        (xy 0.349 -0.535)
        (xy 0.548 -0.535)
      )

      (stroke (width 0.001) (type solid)) (fill solid) (layer "F.Paste"))
    (fp_poly
      (pts
        (xy 0.548 1.703)
        (xy 0.349 1.703)
        (xy 0.349 0.685)
        (xy 0.548 0.685)
      )

      (stroke (width 0.001) (type solid)) (fill solid) (layer "F.Paste"))
    (fp_poly
      (pts
        (xy -1.103 -1.706)
        (xy -1.355 -1.706)
        (xy -1.355 -1.351)
        (xy -1.702 -1.351)
        (xy -1.702 -1.127)
        (xy -1.103 -1.127)
      )

      (stroke (width 0.001) (type solid)) (fill solid) (layer "F.Paste"))
    (fp_poly
      (pts
        (xy -1.101 1.705)
        (xy -1.355 1.703)
        (xy -1.355 1.348)
        (xy -1.7 1.35)
        (xy -1.7 1.124)
        (xy -1.101 1.124)
      )

      (stroke (width 0.001) (type solid)) (fill solid) (layer "F.Paste"))
    (fp_poly
      (pts
        (xy 1.1 -1.706)
        (xy 1.352 -1.706)
        (xy 1.352 -1.351)
        (xy 1.699 -1.351)
        (xy 1.699 -1.125)
        (xy 1.1 -1.125)
      )

      (stroke (width 0.001) (type solid)) (fill solid) (layer "F.Paste"))
    (fp_poly
      (pts
        (xy 1.1 1.705)
        (xy 1.352 1.703)
        (xy 1.352 1.348)
        (xy 1.699 1.35)
        (xy 1.699 1.124)
        (xy 1.1 1.124)
      )

      (stroke (width 0.001) (type solid)) (fill solid) (layer "F.Paste"))
    (fp_line (start -1.932 -1.932) (end -1.932 -1.597)
      (stroke (width 0.15) (type solid)) (layer "F.SilkS"))
    (fp_line (start -1.932 1.596) (end -1.932 1.929)
      (stroke (width 0.15) (type solid)) (layer "F.SilkS"))
    (fp_line (start -1.932 1.929) (end -1.621 1.929)
      (stroke (width 0.15) (type solid)) (layer "F.SilkS"))
    (fp_line (start -1.621 -1.932) (end -1.932 -1.932)
      (stroke (width 0.15) (type solid)) (layer "F.SilkS"))
    (fp_line (start 1.618 1.929) (end 1.929 1.929)
      (stroke (width 0.15) (type solid)) (layer "F.SilkS"))
    (fp_line (start 1.929 -1.932) (end 1.618 -1.932)
      (stroke (width 0.15) (type solid)) (layer "F.SilkS"))
    (fp_line (start 1.929 -1.597) (end 1.929 -1.932)
      (stroke (width 0.15) (type solid)) (layer "F.SilkS"))
    (fp_line (start 1.929 1.929) (end 1.929 1.596)
      (stroke (width 0.15) (type solid)) (layer "F.SilkS"))
    (fp_circle (center -2.3 -1.25) (end -2.25 -1.2)
      (stroke (width 0.15) (type solid)) (fill solid) (layer "F.SilkS"))
    (fp_circle (center -2.246 -1.258) (end -2.19 -1.258)
      (stroke (width 0.15) (type solid)) (fill none) (layer "F.SilkS"))
    (fp_rect (start -2 -2) (end 2 2)
      (stroke (width 0.05) (type solid)) (fill none) (layer "F.CrtYd"))
    (fp_line (start -1.551 -0.802) (end -1.551 1.548)
      (stroke (width 0.15) (type solid)) (layer "F.Fab"))
    (fp_line (start -1.551 -0.802) (end -0.802 -1.551)
      (stroke (width 0.15) (type solid)) (layer "F.Fab"))
    (fp_line (start -1.551 1.548) (end 1.548 1.548)
      (stroke (width 0.15) (type solid)) (layer "F.Fab"))
    (fp_line (start 1.548 -1.551) (end -0.802 -1.551)
      (stroke (width 0.15) (type solid)) (layer "F.Fab"))
    (fp_line (start 1.548 1.548) (end 1.548 -1.551)
      (stroke (width 0.15) (type solid)) (layer "F.Fab"))
    (pad "1" smd custom (at -1.401 -1.25 90) (size 0.25 0.6) (layers "F.Cu" "F.Mask")
      (net 301 "VDD1V2") (pinfunction "VLDOIN") (pintype "power_in")
      (options (clearance outline) (anchor rect))
      (primitives
        (gr_poly
          (pts
            (xy 0.4548 0.3)
            (xy 0.454997 0.016207)
            (xy 0.124997 0.016207)
            (xy 0.125 -0.3)
            (xy -0.125 -0.3)
            (xy -0.125 0.3)
          )
          (width 0.001) (fill yes))
        (gr_poly
          (pts
            (xy 0.4548 0.3)
            (xy 0.454997 0.016207)
            (xy 0.124997 0.016207)
            (xy 0.125 -0.3)
            (xy -0.125 -0.3)
            (xy -0.125 0.3)
          )
          (width 0.001) (fill yes))
      ))
    (pad "2" smd rect (at -1.401 -0.751 90) (size 0.25 0.6) (layers "F.Cu" "F.Paste" "F.Mask")
      (net 299 "VCC0V6") (pinfunction "VTT") (pintype "input"))
    (pad "3" smd rect (at -1.401 -0.25 90) (size 0.25 0.6) (layers "F.Cu" "F.Paste" "F.Mask")
      (net 9 "GND") (pinfunction "AGND") (pintype "power_in"))
    (pad "4" smd rect (at -1.401 0.248 90) (size 0.25 0.6) (layers "F.Cu" "F.Paste" "F.Mask")
      (net 616 "Net-(U2-VTTSNS)") (pinfunction "VTTSNS") (pintype "input"))
    (pad "5" smd rect (at -1.401 0.749 90) (size 0.25 0.6) (layers "F.Cu" "F.Paste" "F.Mask")
      (net 301 "VDD1V2") (pinfunction "VDDQSNS") (pintype "input"))
    (pad "6" smd custom (at -1.401 1.249 90) (size 0.25 0.6) (layers "F.Cu" "F.Paste" "F.Mask")
      (net 305 "/Supply/VTTREF") (pinfunction "VTTREF") (pintype "input")
      (options (clearance outline) (anchor rect))
      (primitives
        (gr_poly
          (pts
            (xy -0.4548 0.3)
            (xy -0.454997 0.016207)
            (xy -0.124997 0.016207)
            (xy -0.125 -0.3)
            (xy 0.125 -0.3)
            (xy 0.125 0.3)
          )
          (width 0.001) (fill yes))
        (gr_poly
          (pts
            (xy -0.4548 0.3)
            (xy -0.454997 0.016207)
            (xy -0.124997 0.016207)
            (xy -0.125 -0.3)
            (xy 0.125 -0.3)
            (xy 0.125 0.3)
          )
          (width 0.001) (fill yes))
      ))
    (pad "7" smd rect (at -0.452 0.583) (size 0.2 2.238) (layers "F.Cu" "F.Mask")
      (net 103 "VIN") (pinfunction "PVIN") (pintype "power_in"))
    (pad "8" smd rect (at 0 1.354) (size 0.2 0.7) (layers "F.Cu" "F.Paste" "F.Mask")
      (net 613 "Net-(U2-PGOOD)") (pinfunction "PGOOD") (pintype "output"))
    (pad "9" smd rect (at 0.45 0.583) (size 0.2 2.238) (layers "F.Cu" "F.Mask")
      (net 9 "GND") (pinfunction "PGND") (pintype "power_in"))
    (pad "10" smd custom (at 1.398 1.249 270) (size 0.25 0.6) (layers "F.Cu" "F.Mask")
      (net 793 "/Supply/VTT_CNTL") (pinfunction "VTT_CNTL") (pintype "input")
      (options (clearance outline) (anchor rect))
      (primitives
        (gr_poly
          (pts
            (xy 0.4548 0.3)
            (xy 0.454997 0.016207)
            (xy 0.124997 0.016207)
            (xy 0.125 -0.3)
            (xy -0.125 -0.3)
            (xy -0.125 0.3)
          )
          (width 0.001) (fill yes))
        (gr_poly
          (pts
            (xy 0.4548 0.3)
            (xy 0.454997 0.016207)
            (xy 0.124997 0.016207)
            (xy 0.125 -0.3)
            (xy -0.125 -0.3)
            (xy -0.125 0.3)
          )
          (width 0.001) (fill yes))
      ))
    (pad "11" smd rect (at 1.398 0.749 90) (size 0.25 0.6096) (layers "F.Cu" "F.Paste" "F.Mask")
      (net 794 "/Supply/SLP_S4") (pinfunction "SLP_S4") (pintype "input"))
    (pad "12" smd rect (at 1.398 0.248 90) (size 0.25 0.6096) (layers "F.Cu" "F.Paste" "F.Mask")
      (net 303 "VCC2V5") (pinfunction "VPPSNS") (pintype "input"))
    (pad "13" smd rect (at 1.398 -0.25 90) (size 0.25 0.6096) (layers "F.Cu" "F.Paste" "F.Mask")
      (net 307 "5V0_SYS") (pinfunction "VCC_5V") (pintype "power_in"))
    (pad "14" smd rect (at 1.398 -0.751 90) (size 0.25 0.6) (layers "F.Cu" "F.Paste" "F.Mask")
      (net 307 "5V0_SYS") (pinfunction "PVIN_VPP") (pintype "power_in"))
    (pad "15" smd custom (at 1.398 -1.25 270) (size 0.25 0.6) (layers "F.Cu" "F.Mask")
      (net 571 "Net-(U2-SW_VPP)") (pinfunction "SW_VPP") (pintype "input")
      (options (clearance outline) (anchor rect))
      (primitives
        (gr_poly
          (pts
            (xy -0.4548 0.3)
            (xy -0.454997 0.016207)
            (xy -0.124997 0.016207)
            (xy -0.125 -0.3)
            (xy 0.125 -0.3)
            (xy 0.125 0.3)
          )
          (width 0.001) (fill yes))
        (gr_poly
          (pts
            (xy -0.4548 0.3)
            (xy -0.454997 0.016207)
            (xy -0.124997 0.016207)
            (xy -0.125 -0.3)
            (xy 0.125 -0.3)
            (xy 0.125 0.3)
          )
          (width 0.001) (fill yes))
      ))
    (pad "16" smd rect (at 0.65 -1.401) (size 0.2 0.6096) (layers "F.Cu" "F.Paste" "F.Mask")
      (net 9 "GND") (pinfunction "PGND") (pintype "passive"))
    (pad "17" smd rect (at 0 -0.585) (size 0.2 2.243) (layers "F.Cu" "F.Mask")
      (net 1 "Net-(U2-SW)") (pinfunction "SW") (pintype "input"))
    (pad "18" smd rect (at -0.652 -1.401) (size 0.2 0.6096) (layers "F.Cu" "F.Paste" "F.Mask")
      (net 601 "Net-(U2-BST)") (pinfunction "BST") (pintype "input"))
  )
	(footprint "data-center-rdimm-ddr4-tester-footprints:KEMET_D" (layer "F.Cu")
    (at 141.186328 78.810008 180)
    (descr "Capacitor SMD KEMET_D")
    (tags "capacitor SMD KEMET_D")
    (property "Author" "Antmicro")
    (property "Dielectric" "")
    (property "License" "Apache-2.0")
    (property "MPN" "T520D337M006ATE045")
    (property "Manufacturer" "KEMET")
    (property "Sheetfile" "fpga-power.kicad_sch")
    (property "Sheetname" "FPGA power")
    (property "Val" "330u")
    (property "Voltage" "")
    (property "ki_description" " ")
    (attr smd)
    (fp_text reference "C26" (at -3.683672 1.470008 180) (layer "F.SilkS")
        (effects (font (size 0.7 0.7) (thickness 0.15)) (justify left bottom))
    )
    (fp_text value "C_330u_KEMET_D" (at 0 3.6 180) (layer "F.Fab") hide
        (effects (font (size 0.7 0.7) (thickness 0.15)) (justify left bottom))
    )
    (fp_text user "Author: Antmicro" (at -4.5 7.6 180) (layer "F.Fab") hide
        (effects (font (size 0.7 0.7) (thickness 0.15)) (justify left bottom))
    )
    (fp_text user "${REFERENCE}" (at -4.5 5.6 180) (layer "F.Fab") hide
        (effects (font (size 0.7 0.7) (thickness 0.15)) (justify left bottom))
    )
    (fp_text user "License: Apache-2.0" (at -4.5 6.6 180) (layer "F.Fab") hide
        (effects (font (size 0.7 0.7) (thickness 0.15)) (justify left bottom))
    )
    (fp_line (start -4.2 -1.55) (end -3.8 -1.55)
      (stroke (width 0.12) (type solid)) (layer "F.SilkS"))
    (fp_line (start -4 -1.75) (end -4 -1.35)
      (stroke (width 0.12) (type solid)) (layer "F.SilkS"))
    (fp_line (start -3.65 -2.15) (end 3.65 -2.15)
      (stroke (width 0.15) (type solid)) (layer "F.SilkS"))
    (fp_line (start -3.65 -1.6) (end -3.65 -2.15)
      (stroke (width 0.15) (type solid)) (layer "F.SilkS"))
    (fp_line (start -3.65 1.6) (end -3.65 2.15)
      (stroke (width 0.15) (type solid)) (layer "F.SilkS"))
    (fp_line (start -3.65 2.15) (end 3.65 2.15)
      (stroke (width 0.15) (type solid)) (layer "F.SilkS"))
    (fp_line (start 3.65 -2.15) (end 3.65 -1.6)
      (stroke (width 0.15) (type solid)) (layer "F.SilkS"))
    (fp_line (start 3.65 2.15) (end 3.65 1.6)
      (stroke (width 0.15) (type solid)) (layer "F.SilkS"))
    (fp_rect (start -4.3 -2.5) (end 4.3 2.5)
      (stroke (width 0.05) (type solid)) (fill none) (layer "F.CrtYd"))
    (fp_rect (start -3.65 -2.15) (end 3.65 2.15)
      (stroke (width 0.15) (type solid)) (fill none) (layer "F.Fab"))
    (pad "1" smd rect (at -3.1 0 180) (size 2.31 2.52) (layers "F.Cu" "F.Paste" "F.Mask")
      (net 147 "1V0_SYS") (pintype "passive"))
    (pad "2" smd rect (at 3.1 0 180) (size 2.31 2.52) (layers "F.Cu" "F.Paste" "F.Mask")
      (net 9 "GND") (pintype "passive"))
  )
	(footprint "data-center-rdimm-ddr4-tester-footprints:C_0603_1608Metric" (layer "F.Cu")
    (at 115.836328 77.560008 180)
    (descr "Capacitor SMD 0603")
    (tags "capacitor 0603")
    (property "Author" "Antmicro")
    (property "Dielectric" "")
    (property "License" "Apache-2.0")
    (property "MPN" "06031C103JAT2A")
    (property "Manufacturer" "AVX")
    (property "Sheetfile" "supply.kicad_sch")
    (property "Sheetname" "Supply")
    (property "Val" "10n")
    (property "Voltage" "")
    (property "ki_description" " ")
    (attr smd)
    (fp_text reference "C109" (at 1.486328 8.600008 180) (layer "F.SilkS")
        (effects (font (size 0.7 0.7) (thickness 0.15)) (justify left bottom))
    )
    (fp_text value "C_10n_0603" (at 0 1.6 180) (layer "F.Fab") hide
        (effects (font (size 0.7 0.7) (thickness 0.15)) (justify left bottom))
    )
    (fp_text user "${REFERENCE}" (at -1.682 3.895 180) (layer "F.Fab") hide
        (effects (font (size 0.7 0.7) (thickness 0.15)) (justify left bottom))
    )
    (fp_text user "Author: Antmicro" (at -1.682 4.894 180) (layer "F.Fab") hide
        (effects (font (size 0.7 0.7) (thickness 0.15)) (justify left bottom))
    )
    (fp_text user "License: Apache-2.0" (at -1.682 5.895 180) (layer "F.Fab") hide
        (effects (font (size 0.7 0.7) (thickness 0.15)) (justify left bottom))
    )
    (fp_line (start -0.3 -0.3) (end 0.3 -0.3)
      (stroke (width 0.15) (type solid)) (layer "F.SilkS"))
    (fp_line (start -0.3 0.3) (end 0.3 0.3)
      (stroke (width 0.15) (type solid)) (layer "F.SilkS"))
    (fp_rect (start -1.24 -0.7) (end 1.24 0.7)
      (stroke (width 0.05) (type solid)) (fill none) (layer "F.CrtYd"))
    (fp_rect (start -0.8 -0.4) (end 0.8 0.4)
      (stroke (width 0.15) (type solid)) (fill none) (layer "F.Fab"))
    (pad "1" smd roundrect (at -0.7 0 180) (size 0.6 0.8) (layers "F.Cu" "F.Paste" "F.Mask") (roundrect_rratio 0.2)
      (net 77 "VDDQ") (pintype "passive"))
    (pad "2" smd roundrect (at 0.7 0 180) (size 0.6 0.8) (layers "F.Cu" "F.Paste" "F.Mask") (roundrect_rratio 0.2)
      (net 9 "GND") (pintype "passive"))
  )
	(footprint "data-center-rdimm-ddr4-tester-footprints:Testpoint_smd_1mm" (layer "F.Cu")
    (at 252.586328 63.610808)
    (property "Author" "Antmicro")
    (property "License" "Apache-2.0")
    (property "MPN" "")
    (property "Manufacturer" "")
    (property "Sheetfile" "DDR4.kicad_sch")
    (property "Sheetname" "DDR4")
    (property "ki_description" "Test Point 1mm")
    (attr exclude_from_pos_files)
    (fp_text reference "TP10" (at 0.463672 0.339192) (layer "F.SilkS")
        (effects (font (size 0.7 0.7) (thickness 0.15)) (justify left bottom))
    )
    (fp_text value "TP_1mm_SMD" (at 0 1.4) (layer "F.Fab") hide
        (effects (font (size 0.7 0.7) (thickness 0.15)) (justify left bottom))
    )
    (fp_text user "License: Apache-2.0" (at -0.5 5.2) (layer "F.Fab") hide
        (effects (font (size 0.7 0.7) (thickness 0.15)) (justify left bottom))
    )
    (fp_text user "${REFERENCE}" (at -0.5 2.8) (layer "F.Fab") hide
        (effects (font (size 0.7 0.7) (thickness 0.15)) (justify left bottom))
    )
    (fp_text user "Author: Antmicro" (at -0.5 4) (layer "F.Fab") hide
        (effects (font (size 0.7 0.7) (thickness 0.15)) (justify left bottom))
    )
    (pad "1" smd circle (at 0 0) (size 1 1) (layers "F.Cu" "F.Mask")
      (net 308 "NC") (pinfunction "1") (pintype "passive"))
  )
)
